(kicad_pcb
	(version 20260206)
	(generator "pcbnew")
	(generator_version "10.0")
	(general
		(thickness 1.6)
		(legacy_teardrops no)
	)
	(paper "A4")
	(title_block
		(title "peb — Lightning_PEB_BRD.brd")
		(comment 1 "Lightning (Wiwynn / Facebook NVMe JBOF) / footprints 1832-1838 of 2563")
	)
	(layers
		(0 "F.Cu" signal "TOP")
		(4 "In1.Cu" signal "L2GND")
		(6 "In2.Cu" signal "L3")
		(8 "In3.Cu" signal "L4VCC")
		(10 "In4.Cu" signal "L5VCC")
		(12 "In5.Cu" signal "L6")
		(14 "In6.Cu" signal "L7GND")
		(2 "B.Cu" signal "BOTTOM")
		(9 "F.Adhes" user "F.Adhesive")
		(11 "B.Adhes" user "B.Adhesive")
		(13 "F.Paste" user "Package Geometry/Pastemask Top")
		(15 "B.Paste" user "Package Geometry/Pastemask Bottom")
		(5 "F.SilkS" user "Ref Des/Silkscreen Top")
		(7 "B.SilkS" user "Ref Des/Silkscreen Bottom")
		(1 "F.Mask" user "Board Geometry/Soldermask Top")
		(3 "B.Mask" user "Board Geometry/Soldermask Bottom")
		(17 "Dwgs.User" user "User.Drawings")
		(19 "Cmts.User" user "User.Comments")
		(21 "Eco1.User" user "User.Eco1")
		(23 "Eco2.User" user "User.Eco2")
		(25 "Edge.Cuts" user "Board Geometry/Outline")
		(27 "Margin" user)
		(31 "F.CrtYd" user "Package Geometry/Place Bound Top")
		(29 "B.CrtYd" user "Package Geometry/Place Bound Bottom")
		(35 "F.Fab" user "Ref Des/Assembly Top")
		(33 "B.Fab" user "Ref Des/Assembly Bottom")
	)
	(footprint ""
		(layer "B.Cu")
		(at 46.609 -112.5982 -90)
		(property "Reference" "C219"
			(at 0 0 90)
			(layer "B.SilkS")
			(hide yes)
			(effects
				(font
					(size 1.27 1.27)
				)
				(justify mirror)
			)
		)
		(property "Value" "SC1U10V2KX-4-GP"
			(at -1.1811 -2.7051 270)
			(unlocked yes)
			(layer "B.Fab")
			(hide yes)
			(effects
				(font
					(size 1.016 1.016)
					(thickness 0.1524)
				)
				(justify mirror)
			)
		)
		(property "Device Type" "C402H22"
			(at -1.1811 -4.2291 270)
			(unlocked yes)
			(layer "B.Fab")
			(hide yes)
			(effects
				(font
					(size 1.016 1.016)
					(thickness 0.1524)
				)
				(justify mirror)
			)
		)
		(duplicate_pad_numbers_are_jumpers no)
		(fp_rect
			(start 0.4318 0.9525)
			(end -0.4318 -0.9525)
			(stroke
				(width 0)
				(type default)
			)
			(fill no)
			(layer "B.CrtYd")
		)
		(fp_rect
			(start 0.4318 0.9525)
			(end -0.4318 -0.9525)
			(stroke
				(width 0)
				(type default)
			)
			(fill no)
			(layer "B.Fab")
		)
		(pad "1" smd custom
			(at 0 -0.4445 90)
			(size 0.1524 0.1524)
			(layers "B.Cu" "B.Mask" "B.Paste")
			(net "P3V3_STBY")
			(options
				(clearance outline)
				(anchor circle)
			)
			(primitives
				(gr_poly
					(pts
						(arc
							(start 0.3048 0.2032)
							(mid 0.275042 0.275042)
							(end 0.2032 0.3048)
						)
						(arc
							(start -0.2032 0.3048)
							(mid -0.275042 0.275042)
							(end -0.3048 0.2032)
						)
						(arc
							(start -0.3048 -0.2032)
							(mid -0.275042 -0.275042)
							(end -0.2032 -0.3048)
						)
						(arc
							(start 0.2032 -0.3048)
							(mid 0.275042 -0.275042)
							(end 0.3048 -0.2032)
						)
					)
					(width 0)
					(fill yes)
				)
			)
		)
		(pad "2" smd custom
			(at 0 0.4445 90)
			(size 0.1524 0.1524)
			(layers "B.Cu" "B.Mask" "B.Paste")
			(net "GND")
			(options
				(clearance outline)
				(anchor circle)
			)
			(primitives
				(gr_poly
					(pts
						(arc
							(start 0.3048 0.2032)
							(mid 0.275042 0.275042)
							(end 0.2032 0.3048)
						)
						(arc
							(start -0.2032 0.3048)
							(mid -0.275042 0.275042)
							(end -0.3048 0.2032)
						)
						(arc
							(start -0.3048 -0.2032)
							(mid -0.275042 -0.275042)
							(end -0.2032 -0.3048)
						)
						(arc
							(start 0.2032 -0.3048)
							(mid 0.275042 -0.275042)
							(end 0.3048 -0.2032)
						)
					)
					(width 0)
					(fill yes)
				)
			)
		)
	)
	(footprint ""
		(layer "B.Cu")
		(at 158.623 -90.0684 90)
		(property "Reference" "C716"
			(at 0 0 90)
			(layer "B.SilkS")
			(hide yes)
			(effects
				(font
					(size 1.27 1.27)
				)
				(justify mirror)
			)
		)
		(property "Value" "SCD1U10V2KX-5GP"
			(at -1.1811 -2.7051 90)
			(unlocked yes)
			(layer "B.Fab")
			(hide yes)
			(effects
				(font
					(size 1.016 1.016)
					(thickness 0.1524)
				)
				(justify mirror)
			)
		)
		(property "Device Type" "C402H22"
			(at -1.1811 -4.2291 90)
			(unlocked yes)
			(layer "B.Fab")
			(hide yes)
			(effects
				(font
					(size 1.016 1.016)
					(thickness 0.1524)
				)
				(justify mirror)
			)
		)
		(duplicate_pad_numbers_are_jumpers no)
		(fp_rect
			(start 0.4318 0.9525)
			(end -0.4318 -0.9525)
			(stroke
				(width 0)
				(type default)
			)
			(fill no)
			(layer "B.CrtYd")
		)
		(fp_rect
			(start 0.4318 0.9525)
			(end -0.4318 -0.9525)
			(stroke
				(width 0)
				(type default)
			)
			(fill no)
			(layer "B.Fab")
		)
		(pad "1" smd custom
			(at 0 -0.4445 270)
			(size 0.1524 0.1524)
			(layers "B.Cu" "B.Mask" "B.Paste")
			(net "P1V8_CLKGEN")
			(options
				(clearance outline)
				(anchor circle)
			)
			(primitives
				(gr_poly
					(pts
						(arc
							(start 0.3048 0.2032)
							(mid 0.275042 0.275042)
							(end 0.2032 0.3048)
						)
						(arc
							(start -0.2032 0.3048)
							(mid -0.275042 0.275042)
							(end -0.3048 0.2032)
						)
						(arc
							(start -0.3048 -0.2032)
							(mid -0.275042 -0.275042)
							(end -0.2032 -0.3048)
						)
						(arc
							(start 0.2032 -0.3048)
							(mid 0.275042 -0.275042)
							(end 0.3048 -0.2032)
						)
					)
					(width 0)
					(fill yes)
				)
			)
		)
		(pad "2" smd custom
			(at 0 0.4445 270)
			(size 0.1524 0.1524)
			(layers "B.Cu" "B.Mask" "B.Paste")
			(net "GND")
			(options
				(clearance outline)
				(anchor circle)
			)
			(primitives
				(gr_poly
					(pts
						(arc
							(start 0.3048 0.2032)
							(mid 0.275042 0.275042)
							(end 0.2032 0.3048)
						)
						(arc
							(start -0.2032 0.3048)
							(mid -0.275042 0.275042)
							(end -0.3048 0.2032)
						)
						(arc
							(start -0.3048 -0.2032)
							(mid -0.275042 -0.275042)
							(end -0.2032 -0.3048)
						)
						(arc
							(start 0.2032 -0.3048)
							(mid 0.275042 -0.275042)
							(end 0.3048 -0.2032)
						)
					)
					(width 0)
					(fill yes)
				)
			)
		)
	)
	(footprint ""
		(layer "B.Cu")
		(at 233.5276 -55.0037 90)
		(property "Reference" "C545"
			(at 0 0 90)
			(layer "B.SilkS")
			(hide yes)
			(effects
				(font
					(size 1.27 1.27)
				)
				(justify mirror)
			)
		)
		(property "Value" "SCD1U16V1KX-1-GP"
			(at 2.8321 -1.7399 90)
			(unlocked yes)
			(layer "B.Fab")
			(hide yes)
			(effects
				(font
					(size 1.016 1.016)
					(thickness 0.1524)
				)
				(justify mirror)
			)
		)
		(property "Device Type" "C0201H13"
			(at 2.8321 -3.2639 90)
			(unlocked yes)
			(layer "B.Fab")
			(hide yes)
			(effects
				(font
					(size 1.016 1.016)
					(thickness 0.1524)
				)
				(justify mirror)
			)
		)
		(duplicate_pad_numbers_are_jumpers no)
		(fp_rect
			(start 0.2794 0.6477)
			(end -0.2794 -0.6477)
			(stroke
				(width 0)
				(type default)
			)
			(fill no)
			(layer "B.CrtYd")
		)
		(fp_rect
			(start 0.2794 0.6477)
			(end -0.2794 -0.6477)
			(stroke
				(width 0)
				(type default)
			)
			(fill no)
			(layer "B.Fab")
		)
		(pad "1" smd custom
			(at 0 -0.2794 270)
			(size 0.0762 0.0762)
			(layers "B.Cu" "B.Mask" "B.Paste")
			(net "DUT_AVD_PCIE")
			(options
				(clearance outline)
				(anchor circle)
			)
			(primitives
				(gr_poly
					(pts
						(arc
							(start 0.1524 0.127)
							(mid 0.137521 0.162921)
							(end 0.1016 0.1778)
						)
						(arc
							(start -0.1016 0.1778)
							(mid -0.137521 0.162921)
							(end -0.1524 0.127)
						)
						(arc
							(start -0.1524 -0.127)
							(mid -0.137521 -0.162921)
							(end -0.1016 -0.1778)
						)
						(arc
							(start 0.1016 -0.1778)
							(mid 0.137521 -0.162921)
							(end 0.1524 -0.127)
						)
					)
					(width 0)
					(fill yes)
				)
			)
		)
		(pad "2" smd custom
			(at 0 0.2794 270)
			(size 0.0762 0.0762)
			(layers "B.Cu" "B.Mask" "B.Paste")
			(net "GND")
			(options
				(clearance outline)
				(anchor circle)
			)
			(primitives
				(gr_poly
					(pts
						(arc
							(start 0.1524 0.127)
							(mid 0.137521 0.162921)
							(end 0.1016 0.1778)
						)
						(arc
							(start -0.1016 0.1778)
							(mid -0.137521 0.162921)
							(end -0.1524 0.127)
						)
						(arc
							(start -0.1524 -0.127)
							(mid -0.137521 -0.162921)
							(end -0.1016 -0.1778)
						)
						(arc
							(start 0.1016 -0.1778)
							(mid 0.137521 -0.162921)
							(end 0.1524 -0.127)
						)
					)
					(width 0)
					(fill yes)
				)
			)
		)
	)
	(footprint ""
		(layer "B.Cu")
		(at 333.915512 -184.878218 180)
		(property "Reference" "R4165"
			(at 0 0 0)
			(layer "B.SilkS")
			(hide yes)
			(effects
				(font
					(size 1.27 1.27)
				)
				(justify mirror)
			)
		)
		(property "Value" "4K7R2F-GP"
			(at -0.064008 -3.993896 180)
			(unlocked yes)
			(layer "B.Fab")
			(hide yes)
			(effects
				(font
					(size 1.016 1.016)
					(thickness 0.1524)
				)
				(justify mirror)
			)
		)
		(property "Device Type" "R402H16"
			(at -0.064008 -5.517896 180)
			(unlocked yes)
			(layer "B.Fab")
			(hide yes)
			(effects
				(font
					(size 1.016 1.016)
					(thickness 0.1524)
				)
				(justify mirror)
			)
		)
		(duplicate_pad_numbers_are_jumpers no)
		(fp_line
			(start 0.508 -0.9398)
			(end 0.508 0.9398)
			(stroke
				(width 0.1524)
				(type default)
			)
			(layer "B.SilkS")
		)
		(fp_line
			(start -0.508 -0.9398)
			(end 0.508 -0.9398)
			(stroke
				(width 0.1524)
				(type default)
			)
			(layer "B.SilkS")
		)
		(fp_rect
			(start 0.508 0.9398)
			(end -0.508 -0.9398)
			(stroke
				(width 0)
				(type default)
			)
			(fill no)
			(layer "B.CrtYd")
		)
		(fp_rect
			(start 0.508 0.9398)
			(end -0.508 -0.9398)
			(stroke
				(width 0)
				(type default)
			)
			(fill no)
			(layer "B.Fab")
		)
		(pad "1" smd custom
			(at 0 -0.4445)
			(size 0.1397 0.1397)
			(layers "B.Cu" "B.Mask" "B.Paste")
			(net "BMC_PERST#15")
			(options
				(clearance outline)
				(anchor circle)
			)
			(primitives
				(gr_poly
					(pts
						(arc
							(start -0.1778 0.2794)
							(mid -0.249642 0.249642)
							(end -0.2794 0.1778)
						)
						(arc
							(start -0.2794 -0.1778)
							(mid -0.249642 -0.249642)
							(end -0.1778 -0.2794)
						)
						(arc
							(start 0.1778 -0.2794)
							(mid 0.249642 -0.249642)
							(end 0.2794 -0.1778)
						)
						(arc
							(start 0.2794 0.1778)
							(mid 0.249642 0.249642)
							(end 0.1778 0.2794)
						)
					)
					(width 0)
					(fill yes)
				)
			)
		)
		(pad "2" smd custom
			(at 0 0.4445)
			(size 0.1397 0.1397)
			(layers "B.Cu" "B.Mask" "B.Paste")
			(net "P3V3_STBY")
			(options
				(clearance outline)
				(anchor circle)
			)
			(primitives
				(gr_poly
					(pts
						(arc
							(start -0.1778 0.2794)
							(mid -0.249642 0.249642)
							(end -0.2794 0.1778)
						)
						(arc
							(start -0.2794 -0.1778)
							(mid -0.249642 -0.249642)
							(end -0.1778 -0.2794)
						)
						(arc
							(start 0.1778 -0.2794)
							(mid 0.249642 -0.249642)
							(end 0.2794 -0.1778)
						)
						(arc
							(start 0.2794 0.1778)
							(mid 0.249642 0.249642)
							(end 0.1778 0.2794)
						)
					)
					(width 0)
					(fill yes)
				)
			)
		)
	)
	(footprint ""
		(layer "B.Cu")
		(at 53.975508 -121.823226 -90)
		(property "Reference" "R246"
			(at 0 0 90)
			(layer "B.SilkS")
			(hide yes)
			(effects
				(font
					(size 1.27 1.27)
				)
				(justify mirror)
			)
		)
		(property "Value" "0R2J-2-GP"
			(at -0.064008 -3.993896 270)
			(unlocked yes)
			(layer "B.Fab")
			(hide yes)
			(effects
				(font
					(size 1.016 1.016)
					(thickness 0.1524)
				)
				(justify mirror)
			)
		)
		(property "Device Type" "R402H16"
			(at -0.064008 -5.517896 270)
			(unlocked yes)
			(layer "B.Fab")
			(hide yes)
			(effects
				(font
					(size 1.016 1.016)
					(thickness 0.1524)
				)
				(justify mirror)
			)
		)
		(duplicate_pad_numbers_are_jumpers no)
		(fp_line
			(start -0.508 -0.9398)
			(end 0.508 -0.9398)
			(stroke
				(width 0.1524)
				(type default)
			)
			(layer "B.SilkS")
		)
		(fp_line
			(start 0.508 -0.9398)
			(end 0.508 0.9398)
			(stroke
				(width 0.1524)
				(type default)
			)
			(layer "B.SilkS")
		)
		(fp_rect
			(start 0.508 0.9398)
			(end -0.508 -0.9398)
			(stroke
				(width 0)
				(type default)
			)
			(fill no)
			(layer "B.CrtYd")
		)
		(fp_rect
			(start 0.508 0.9398)
			(end -0.508 -0.9398)
			(stroke
				(width 0)
				(type default)
			)
			(fill no)
			(layer "B.Fab")
		)
		(pad "1" smd custom
			(at 0 -0.4445 90)
			(size 0.1397 0.1397)
			(layers "B.Cu" "B.Mask" "B.Paste")
			(net "BMC_I2C5_D_PEB_DEVICE_SCL")
			(options
				(clearance outline)
				(anchor circle)
			)
			(primitives
				(gr_poly
					(pts
						(arc
							(start -0.1778 0.2794)
							(mid -0.249642 0.249642)
							(end -0.2794 0.1778)
						)
						(arc
							(start -0.2794 -0.1778)
							(mid -0.249642 -0.249642)
							(end -0.1778 -0.2794)
						)
						(arc
							(start 0.1778 -0.2794)
							(mid 0.249642 -0.249642)
							(end 0.2794 -0.1778)
						)
						(arc
							(start 0.2794 0.1778)
							(mid 0.249642 0.249642)
							(end 0.1778 0.2794)
						)
					)
					(width 0)
					(fill yes)
				)
			)
		)
		(pad "2" smd custom
			(at 0 0.4445 90)
			(size 0.1397 0.1397)
			(layers "B.Cu" "B.Mask" "B.Paste")
			(net "BMC0_SMB5_CLK")
			(options
				(clearance outline)
				(anchor circle)
			)
			(primitives
				(gr_poly
					(pts
						(arc
							(start -0.1778 0.2794)
							(mid -0.249642 0.249642)
							(end -0.2794 0.1778)
						)
						(arc
							(start -0.2794 -0.1778)
							(mid -0.249642 -0.249642)
							(end -0.1778 -0.2794)
						)
						(arc
							(start 0.1778 -0.2794)
							(mid 0.249642 -0.249642)
							(end 0.2794 -0.1778)
						)
						(arc
							(start 0.2794 0.1778)
							(mid 0.249642 0.249642)
							(end 0.1778 0.2794)
						)
					)
					(width 0)
					(fill yes)
				)
			)
		)
	)
	(footprint ""
		(layer "B.Cu")
		(at 234.5944 -31.9786)
		(property "Reference" "C476"
			(at 0 0 0)
			(layer "B.SilkS")
			(hide yes)
			(effects
				(font
					(size 1.27 1.27)
				)
				(justify mirror)
			)
		)
		(property "Value" "SCD1U16V1KX-1-GP"
			(at 2.8321 -1.7399 0)
			(unlocked yes)
			(layer "B.Fab")
			(hide yes)
			(effects
				(font
					(size 1.016 1.016)
					(thickness 0.1524)
				)
				(justify mirror)
			)
		)
		(property "Device Type" "C0201H13"
			(at 2.8321 -3.2639 0)
			(unlocked yes)
			(layer "B.Fab")
			(hide yes)
			(effects
				(font
					(size 1.016 1.016)
					(thickness 0.1524)
				)
				(justify mirror)
			)
		)
		(duplicate_pad_numbers_are_jumpers no)
		(fp_rect
			(start 0.2794 0.6477)
			(end -0.2794 -0.6477)
			(stroke
				(width 0)
				(type default)
			)
			(fill no)
			(layer "B.CrtYd")
		)
		(fp_rect
			(start 0.2794 0.6477)
			(end -0.2794 -0.6477)
			(stroke
				(width 0)
				(type default)
			)
			(fill no)
			(layer "B.Fab")
		)
		(pad "1" smd custom
			(at 0 -0.2794 180)
			(size 0.0762 0.0762)
			(layers "B.Cu" "B.Mask" "B.Paste")
			(net "DUT_VDDO")
			(options
				(clearance outline)
				(anchor circle)
			)
			(primitives
				(gr_poly
					(pts
						(arc
							(start 0.1524 0.127)
							(mid 0.137521 0.162921)
							(end 0.1016 0.1778)
						)
						(arc
							(start -0.1016 0.1778)
							(mid -0.137521 0.162921)
							(end -0.1524 0.127)
						)
						(arc
							(start -0.1524 -0.127)
							(mid -0.137521 -0.162921)
							(end -0.1016 -0.1778)
						)
						(arc
							(start 0.1016 -0.1778)
							(mid 0.137521 -0.162921)
							(end 0.1524 -0.127)
						)
					)
					(width 0)
					(fill yes)
				)
			)
		)
		(pad "2" smd custom
			(at 0 0.2794 180)
			(size 0.0762 0.0762)
			(layers "B.Cu" "B.Mask" "B.Paste")
			(net "GND")
			(options
				(clearance outline)
				(anchor circle)
			)
			(primitives
				(gr_poly
					(pts
						(arc
							(start 0.1524 0.127)
							(mid 0.137521 0.162921)
							(end 0.1016 0.1778)
						)
						(arc
							(start -0.1016 0.1778)
							(mid -0.137521 0.162921)
							(end -0.1524 0.127)
						)
						(arc
							(start -0.1524 -0.127)
							(mid -0.137521 -0.162921)
							(end -0.1016 -0.1778)
						)
						(arc
							(start 0.1016 -0.1778)
							(mid 0.137521 -0.162921)
							(end 0.1524 -0.127)
						)
					)
					(width 0)
					(fill yes)
				)
			)
		)
	)
	(footprint ""
		(layer "B.Cu")
		(at 296.064178 -209.04454 90)
		(property "Reference" "C4152"
			(at 0 0 90)
			(layer "B.SilkS")
			(hide yes)
			(effects
				(font
					(size 1.27 1.27)
				)
				(justify mirror)
			)
		)
		(property "Value" "SCD1U25V3KX-GP"
			(at 0 -2.8194 90)
			(unlocked yes)
			(layer "B.Fab")
			(hide yes)
			(effects
				(font
					(size 1.016 1.016)
					(thickness 0.1524)
				)
				(justify mirror)
			)
		)
		(property "Device Type" "C603H36"
			(at 0 -4.3434 90)
			(unlocked yes)
			(layer "B.Fab")
			(hide yes)
			(effects
				(font
					(size 1.016 1.016)
					(thickness 0.1524)
				)
				(justify mirror)
			)
		)
		(duplicate_pad_numbers_are_jumpers no)
		(fp_line
			(start -0.508 0)
			(end 0.508 0)
			(stroke
				(width 0.2032)
				(type default)
			)
			(layer "B.SilkS")
		)
		(fp_rect
			(start 0.5842 1.3335)
			(end -0.5842 -1.3335)
			(stroke
				(width 0)
				(type default)
			)
			(fill no)
			(layer "B.CrtYd")
		)
		(fp_rect
			(start 0.5842 1.3335)
			(end -0.5842 -1.3335)
			(stroke
				(width 0)
				(type default)
			)
			(fill no)
			(layer "B.Fab")
		)
		(pad "1" smd custom
			(at 0 -0.762 270)
			(size 0.2159 0.2159)
			(layers "B.Cu" "B.Mask" "B.Paste")
			(net "GND")
			(options
				(clearance outline)
				(anchor circle)
			)
			(primitives
				(gr_poly
					(pts
						(arc
							(start -0.3302 0.4318)
							(mid -0.402042 0.402042)
							(end -0.4318 0.3302)
						)
						(arc
							(start -0.4318 -0.3302)
							(mid -0.402042 -0.402042)
							(end -0.3302 -0.4318)
						)
						(arc
							(start 0.3302 -0.4318)
							(mid 0.402042 -0.402042)
							(end 0.4318 -0.3302)
						)
						(arc
							(start 0.4318 0.3302)
							(mid 0.402042 0.402042)
							(end 0.3302 0.4318)
						)
					)
					(width 0)
					(fill yes)
				)
			)
		)
		(pad "2" smd custom
			(at 0 0.762 270)
			(size 0.2159 0.2159)
			(layers "B.Cu" "B.Mask" "B.Paste")
			(net "SSD_PWREN4_R")
			(options
				(clearance outline)
				(anchor circle)
			)
			(primitives
				(gr_poly
					(pts
						(arc
							(start -0.3302 0.4318)
							(mid -0.402042 0.402042)
							(end -0.4318 0.3302)
						)
						(arc
							(start -0.4318 -0.3302)
							(mid -0.402042 -0.402042)
							(end -0.3302 -0.4318)
						)
						(arc
							(start 0.3302 -0.4318)
							(mid 0.402042 -0.402042)
							(end 0.4318 -0.3302)
						)
						(arc
							(start 0.4318 0.3302)
							(mid 0.402042 0.402042)
							(end 0.3302 0.4318)
						)
					)
					(width 0)
					(fill yes)
				)
			)
		)
	)
)
